# S9S_MB_2U (Grand Teton) — schematic netlist excerpt (pin names and nets, part order shuffled) for the footprints in the layout excerpt that follows; sources: Cadence DE-HDL packaged netlist, KiCad conversion of 03242023_DA0F0TMBIJ0_F0T_Motherboard_J_brd_V01_OCP.brd

R4038  Q_RES  4.32K 1% CHIP  pkg 0402LF  page 225 : A = P3V3 ; B = P0V62_CPU0_ERRS_U306_VREF
C1865  Q_CAP  0.1UF 25V 10% X7R  pkg 0402  page 166 : A = P3V3_AUX ; B = GND

(kicad_pcb
	(version 20260206)
	(generator "pcbnew")
	(generator_version "10.0")
	(general
		(thickness 1.6)
		(legacy_teardrops no)
	)
	(paper "A4")
	(title_block
		(title "03242023_DA0F0TMBIJ0_F0T_Motherboard_J_brd_V01_OCP.brd")
		(comment 1 "Grand Teton / footprints 4122-4123 of 6105")
	)
	(layers
		(0 "F.Cu" signal "TOP")
		(4 "In1.Cu" signal "GND")
		(6 "In2.Cu" signal "IN1")
		(8 "In3.Cu" signal "GND1")
		(10 "In4.Cu" signal "IN2")
		(12 "In5.Cu" signal "GND2")
		(14 "In6.Cu" signal "IN3")
		(16 "In7.Cu" signal "GND3")
		(18 "In8.Cu" signal "VCC")
		(20 "In9.Cu" signal "VCC1")
		(22 "In10.Cu" signal "GND4")
		(24 "In11.Cu" signal "IN4")
		(26 "In12.Cu" signal "GND5")
		(28 "In13.Cu" signal "IN5")
		(30 "In14.Cu" signal "GND6")
		(32 "In15.Cu" signal "IN6")
		(34 "In16.Cu" signal "GND7")
		(2 "B.Cu" signal "BOTTOM")
		(9 "F.Adhes" user "F.Adhesive")
		(11 "B.Adhes" user "B.Adhesive")
		(13 "F.Paste" user "Package Geometry/Pastemask Top")
		(15 "B.Paste" user "Package Geometry/Pastemask Bottom")
		(5 "F.SilkS" user "Ref Des/Silkscreen Top")
		(7 "B.SilkS" user "Ref Des/Silkscreen Bottom")
		(1 "F.Mask" user "Board Geometry/Soldermask Top")
		(3 "B.Mask" user "Board Geometry/Soldermask Bottom")
		(17 "Dwgs.User" user "User.Drawings")
		(19 "Cmts.User" user "User.Comments")
		(21 "Eco1.User" user "User.Eco1")
		(23 "Eco2.User" user "User.Eco2")
		(25 "Edge.Cuts" user "Board Geometry/Outline")
		(27 "Margin" user)
		(31 "F.CrtYd" user "Package Geometry/Place Bound Top")
		(29 "B.CrtYd" user "Package Geometry/Place Bound Bottom")
		(35 "F.Fab" user "Ref Des/Assembly Top")
		(33 "B.Fab" user "Ref Des/Assembly Bottom")
	)
	(footprint ""
		(layer "F.Cu")
		(at 19.119596 -393.215876 90)
		(property "Reference" "C1865"
			(at 0 0 90)
			(layer "F.SilkS")
			(hide yes)
			(effects
				(font
					(size 1.27 1.27)
				)
			)
		)
		(property "Value" ""
			(at 0 0 90)
			(layer "F.Fab")
			(effects
				(font
					(size 1.27 1.27)
				)
			)
		)
		(duplicate_pad_numbers_are_jumpers no)
		(fp_line
			(start 0.7874 -0.4064)
			(end 0.7874 0.4064)
			(stroke
				(width 0.1524)
				(type default)
			)
			(layer "F.SilkS")
		)
		(fp_line
			(start -0.7874 -0.4064)
			(end 0.7874 -0.4064)
			(stroke
				(width 0.1524)
				(type default)
			)
			(layer "F.SilkS")
		)
		(fp_line
			(start 0.7874 0.4064)
			(end -0.7874 0.4064)
			(stroke
				(width 0.1524)
				(type default)
			)
			(layer "F.SilkS")
		)
		(fp_line
			(start -0.7874 0.4064)
			(end -0.7874 -0.4064)
			(stroke
				(width 0.1524)
				(type default)
			)
			(layer "F.SilkS")
		)
		(fp_line
			(start -0.12065 -0.305054)
			(end -0.12065 -0.2794)
			(stroke
				(width 0.1)
				(type default)
			)
			(layer "F.Fab")
		)
		(fp_line
			(start -0.67945 -0.305054)
			(end -0.12065 -0.305054)
			(stroke
				(width 0.1)
				(type default)
			)
			(layer "F.Fab")
		)
		(fp_line
			(start 0.67945 -0.3048)
			(end 0.67945 0.3048)
			(stroke
				(width 0.1)
				(type default)
			)
			(layer "F.Fab")
		)
		(fp_line
			(start 0.12065 -0.3048)
			(end 0.67945 -0.3048)
			(stroke
				(width 0.1)
				(type default)
			)
			(layer "F.Fab")
		)
		(fp_line
			(start 0.12065 -0.2794)
			(end 0.12065 -0.3048)
			(stroke
				(width 0.1)
				(type default)
			)
			(layer "F.Fab")
		)
		(fp_line
			(start -0.12065 -0.2794)
			(end 0.12065 -0.2794)
			(stroke
				(width 0.1)
				(type default)
			)
			(layer "F.Fab")
		)
		(fp_line
			(start 0.120396 0.2794)
			(end -0.12065 0.2794)
			(stroke
				(width 0.1)
				(type default)
			)
			(layer "F.Fab")
		)
		(fp_line
			(start -0.12065 0.2794)
			(end -0.12065 0.3048)
			(stroke
				(width 0.1)
				(type default)
			)
			(layer "F.Fab")
		)
		(fp_line
			(start 0.67945 0.3048)
			(end 0.120396 0.3048)
			(stroke
				(width 0.1)
				(type default)
			)
			(layer "F.Fab")
		)
		(fp_line
			(start 0.120396 0.3048)
			(end 0.120396 0.2794)
			(stroke
				(width 0.1)
				(type default)
			)
			(layer "F.Fab")
		)
		(fp_line
			(start -0.12065 0.3048)
			(end -0.67945 0.3048)
			(stroke
				(width 0.1)
				(type default)
			)
			(layer "F.Fab")
		)
		(fp_line
			(start -0.67945 0.3048)
			(end -0.67945 -0.305054)
			(stroke
				(width 0.1)
				(type default)
			)
			(layer "F.Fab")
		)
		(pad "1" smd circle
			(at -0.40005 0 90)
			(size 0 0)
			(layers "F.Cu" "F.Mask" "F.Paste")
			(net "P3V3_AUX")
		)
		(pad "2" smd circle
			(at 0.40005 0 90)
			(size 0 0)
			(layers "F.Cu" "F.Mask" "F.Paste")
			(net "GND")
		)
	)
	(footprint ""
		(layer "F.Cu")
		(at 142.0622 -104.116378 -90)
		(property "Reference" "R4038"
			(at 0 0 270)
			(layer "F.SilkS")
			(hide yes)
			(effects
				(font
					(size 1.27 1.27)
				)
			)
		)
		(property "Value" ""
			(at 0 0 270)
			(layer "F.Fab")
			(effects
				(font
					(size 1.27 1.27)
				)
			)
		)
		(duplicate_pad_numbers_are_jumpers no)
		(fp_line
			(start -0.7874 0.4064)
			(end -0.7874 -0.4064)
			(stroke
				(width 0.1524)
				(type default)
			)
			(layer "F.SilkS")
		)
		(fp_line
			(start 0.7874 0.4064)
			(end -0.7874 0.4064)
			(stroke
				(width 0.1524)
				(type default)
			)
			(layer "F.SilkS")
		)
		(fp_line
			(start -0.7874 -0.4064)
			(end 0.7874 -0.4064)
			(stroke
				(width 0.1524)
				(type default)
			)
			(layer "F.SilkS")
		)
		(fp_line
			(start 0.7874 -0.4064)
			(end 0.7874 0.4064)
			(stroke
				(width 0.1524)
				(type default)
			)
			(layer "F.SilkS")
		)
		(fp_line
			(start -0.67945 0.3048)
			(end -0.67945 -0.305054)
			(stroke
				(width 0.1)
				(type default)
			)
			(layer "F.Fab")
		)
		(fp_line
			(start -0.12065 0.3048)
			(end -0.67945 0.3048)
			(stroke
				(width 0.1)
				(type default)
			)
			(layer "F.Fab")
		)
		(fp_line
			(start 0.120396 0.3048)
			(end 0.120396 0.2794)
			(stroke
				(width 0.1)
				(type default)
			)
			(layer "F.Fab")
		)
		(fp_line
			(start 0.67945 0.3048)
			(end 0.120396 0.3048)
			(stroke
				(width 0.1)
				(type default)
			)
			(layer "F.Fab")
		)
		(fp_line
			(start -0.12065 0.2794)
			(end -0.12065 0.3048)
			(stroke
				(width 0.1)
				(type default)
			)
			(layer "F.Fab")
		)
		(fp_line
			(start 0.120396 0.2794)
			(end -0.12065 0.2794)
			(stroke
				(width 0.1)
				(type default)
			)
			(layer "F.Fab")
		)
		(fp_line
			(start -0.12065 -0.2794)
			(end 0.12065 -0.2794)
			(stroke
				(width 0.1)
				(type default)
			)
			(layer "F.Fab")
		)
		(fp_line
			(start 0.12065 -0.2794)
			(end 0.12065 -0.3048)
			(stroke
				(width 0.1)
				(type default)
			)
			(layer "F.Fab")
		)
		(fp_line
			(start 0.12065 -0.3048)
			(end 0.67945 -0.3048)
			(stroke
				(width 0.1)
				(type default)
			)
			(layer "F.Fab")
		)
		(fp_line
			(start 0.67945 -0.3048)
			(end 0.67945 0.3048)
			(stroke
				(width 0.1)
				(type default)
			)
			(layer "F.Fab")
		)
		(fp_line
			(start -0.67945 -0.305054)
			(end -0.12065 -0.305054)
			(stroke
				(width 0.1)
				(type default)
			)
			(layer "F.Fab")
		)
		(fp_line
			(start -0.12065 -0.305054)
			(end -0.12065 -0.2794)
			(stroke
				(width 0.1)
				(type default)
			)
			(layer "F.Fab")
		)
		(pad "1" smd circle
			(at -0.40005 0 270)
			(size 0 0)
			(layers "F.Cu" "F.Mask" "F.Paste")
			(net "P3V3")
		)
		(pad "2" smd circle
			(at 0.40005 0 270)
			(size 0 0)
			(layers "F.Cu" "F.Mask" "F.Paste")
			(net "P0V62_CPU0_ERRS_U306_VREF")
		)
	)
)
